# S9S_MB_2U (Grand Teton) — schematic netlist excerpt (pin names and nets, part order shuffled) for the footprints in the layout excerpt that follows; sources: Cadence DE-HDL packaged netlist, KiCad conversion of 03242023_DA0F0TMBIJ0_F0T_Motherboard_J_brd_V01_OCP.brd

PR1322  Q_RES  0 5% CHIP  pkg 0402LF  page 271 : A = PVCCFA_EHV_FIVRA_CPU0_VOS1 ; B = PVCCFA_EHV_FIVRA_CPU0
R1460  Q_RES  2.2K 5% EMPTY  pkg 0402LF  page 241 : A = I3C_BMC_SWB_SDA ; B = P3V3_AUX

(kicad_pcb
	(version 20260206)
	(generator "pcbnew")
	(generator_version "10.0")
	(general
		(thickness 1.6)
		(legacy_teardrops no)
	)
	(paper "A4")
	(title_block
		(title "03242023_DA0F0TMBIJ0_F0T_Motherboard_J_brd_V01_OCP.brd")
		(comment 1 "Grand Teton / footprints 4179-4180 of 6105")
	)
	(layers
		(0 "F.Cu" signal "TOP")
		(4 "In1.Cu" signal "GND")
		(6 "In2.Cu" signal "IN1")
		(8 "In3.Cu" signal "GND1")
		(10 "In4.Cu" signal "IN2")
		(12 "In5.Cu" signal "GND2")
		(14 "In6.Cu" signal "IN3")
		(16 "In7.Cu" signal "GND3")
		(18 "In8.Cu" signal "VCC")
		(20 "In9.Cu" signal "VCC1")
		(22 "In10.Cu" signal "GND4")
		(24 "In11.Cu" signal "IN4")
		(26 "In12.Cu" signal "GND5")
		(28 "In13.Cu" signal "IN5")
		(30 "In14.Cu" signal "GND6")
		(32 "In15.Cu" signal "IN6")
		(34 "In16.Cu" signal "GND7")
		(2 "B.Cu" signal "BOTTOM")
		(9 "F.Adhes" user "F.Adhesive")
		(11 "B.Adhes" user "B.Adhesive")
		(13 "F.Paste" user "Package Geometry/Pastemask Top")
		(15 "B.Paste" user "Package Geometry/Pastemask Bottom")
		(5 "F.SilkS" user "Ref Des/Silkscreen Top")
		(7 "B.SilkS" user "Ref Des/Silkscreen Bottom")
		(1 "F.Mask" user "Board Geometry/Soldermask Top")
		(3 "B.Mask" user "Board Geometry/Soldermask Bottom")
		(17 "Dwgs.User" user "User.Drawings")
		(19 "Cmts.User" user "User.Comments")
		(21 "Eco1.User" user "User.Eco1")
		(23 "Eco2.User" user "User.Eco2")
		(25 "Edge.Cuts" user "Board Geometry/Outline")
		(27 "Margin" user)
		(31 "F.CrtYd" user "Package Geometry/Place Bound Top")
		(29 "B.CrtYd" user "Package Geometry/Place Bound Bottom")
		(35 "F.Fab" user "Ref Des/Assembly Top")
		(33 "B.Fab" user "Ref Des/Assembly Bottom")
	)
	(footprint ""
		(layer "B.Cu")
		(at 174.235872 -13.762228 -90)
		(property "Reference" "R1460"
			(at 0 0 90)
			(layer "B.SilkS")
			(hide yes)
			(effects
				(font
					(size 1.27 1.27)
				)
				(justify mirror)
			)
		)
		(property "Value" ""
			(at 0 0 90)
			(layer "B.Fab")
			(effects
				(font
					(size 1.27 1.27)
				)
				(justify mirror)
			)
		)
		(duplicate_pad_numbers_are_jumpers no)
		(fp_line
			(start -0.7874 0.4064)
			(end 0.7874 0.4064)
			(stroke
				(width 0.1524)
				(type default)
			)
			(layer "B.SilkS")
		)
		(fp_line
			(start 0.7874 0.4064)
			(end 0.7874 -0.4064)
			(stroke
				(width 0.1524)
				(type default)
			)
			(layer "B.SilkS")
		)
		(fp_line
			(start -0.7874 -0.4064)
			(end -0.7874 0.4064)
			(stroke
				(width 0.1524)
				(type default)
			)
			(layer "B.SilkS")
		)
		(fp_line
			(start 0.7874 -0.4064)
			(end -0.7874 -0.4064)
			(stroke
				(width 0.1524)
				(type default)
			)
			(layer "B.SilkS")
		)
		(fp_line
			(start -0.67945 0.3048)
			(end -0.120396 0.3048)
			(stroke
				(width 0.1)
				(type default)
			)
			(layer "B.Fab")
		)
		(fp_line
			(start -0.120396 0.3048)
			(end -0.120396 0.2794)
			(stroke
				(width 0.1)
				(type default)
			)
			(layer "B.Fab")
		)
		(fp_line
			(start 0.12065 0.3048)
			(end 0.67945 0.3048)
			(stroke
				(width 0.1)
				(type default)
			)
			(layer "B.Fab")
		)
		(fp_line
			(start 0.67945 0.3048)
			(end 0.67945 -0.305054)
			(stroke
				(width 0.1)
				(type default)
			)
			(layer "B.Fab")
		)
		(fp_line
			(start -0.120396 0.2794)
			(end 0.12065 0.2794)
			(stroke
				(width 0.1)
				(type default)
			)
			(layer "B.Fab")
		)
		(fp_line
			(start 0.12065 0.2794)
			(end 0.12065 0.3048)
			(stroke
				(width 0.1)
				(type default)
			)
			(layer "B.Fab")
		)
		(fp_line
			(start -0.12065 -0.2794)
			(end -0.12065 -0.3048)
			(stroke
				(width 0.1)
				(type default)
			)
			(layer "B.Fab")
		)
		(fp_line
			(start 0.12065 -0.2794)
			(end -0.12065 -0.2794)
			(stroke
				(width 0.1)
				(type default)
			)
			(layer "B.Fab")
		)
		(fp_line
			(start -0.67945 -0.3048)
			(end -0.67945 0.3048)
			(stroke
				(width 0.1)
				(type default)
			)
			(layer "B.Fab")
		)
		(fp_line
			(start -0.12065 -0.3048)
			(end -0.67945 -0.3048)
			(stroke
				(width 0.1)
				(type default)
			)
			(layer "B.Fab")
		)
		(fp_line
			(start 0.12065 -0.305054)
			(end 0.12065 -0.2794)
			(stroke
				(width 0.1)
				(type default)
			)
			(layer "B.Fab")
		)
		(fp_line
			(start 0.67945 -0.305054)
			(end 0.12065 -0.305054)
			(stroke
				(width 0.1)
				(type default)
			)
			(layer "B.Fab")
		)
		(pad "1" smd circle
			(at 0.40005 0 90)
			(size 0 0)
			(layers "B.Cu" "B.Mask" "B.Paste")
			(net "I3C_BMC_SWB_SDA")
		)
		(pad "2" smd circle
			(at -0.40005 0 90)
			(size 0 0)
			(layers "B.Cu" "B.Mask" "B.Paste")
			(net "P3V3_AUX")
		)
	)
	(footprint ""
		(layer "B.Cu")
		(at 412.007558 -365.383064 -90)
		(property "Reference" "PR1322"
			(at 0 0 90)
			(layer "B.SilkS")
			(hide yes)
			(effects
				(font
					(size 1.27 1.27)
				)
				(justify mirror)
			)
		)
		(property "Value" ""
			(at 0 0 90)
			(layer "B.Fab")
			(effects
				(font
					(size 1.27 1.27)
				)
				(justify mirror)
			)
		)
		(duplicate_pad_numbers_are_jumpers no)
		(fp_line
			(start -0.7874 0.4064)
			(end 0.7874 0.4064)
			(stroke
				(width 0.1524)
				(type default)
			)
			(layer "B.SilkS")
		)
		(fp_line
			(start 0.7874 0.4064)
			(end 0.7874 -0.4064)
			(stroke
				(width 0.1524)
				(type default)
			)
			(layer "B.SilkS")
		)
		(fp_line
			(start -0.7874 -0.4064)
			(end -0.7874 0.4064)
			(stroke
				(width 0.1524)
				(type default)
			)
			(layer "B.SilkS")
		)
		(fp_line
			(start 0.7874 -0.4064)
			(end -0.7874 -0.4064)
			(stroke
				(width 0.1524)
				(type default)
			)
			(layer "B.SilkS")
		)
		(fp_line
			(start -0.67945 0.3048)
			(end -0.120396 0.3048)
			(stroke
				(width 0.1)
				(type default)
			)
			(layer "B.Fab")
		)
		(fp_line
			(start -0.120396 0.3048)
			(end -0.120396 0.2794)
			(stroke
				(width 0.1)
				(type default)
			)
			(layer "B.Fab")
		)
		(fp_line
			(start 0.12065 0.3048)
			(end 0.67945 0.3048)
			(stroke
				(width 0.1)
				(type default)
			)
			(layer "B.Fab")
		)
		(fp_line
			(start 0.67945 0.3048)
			(end 0.67945 -0.305054)
			(stroke
				(width 0.1)
				(type default)
			)
			(layer "B.Fab")
		)
		(fp_line
			(start -0.120396 0.2794)
			(end 0.12065 0.2794)
			(stroke
				(width 0.1)
				(type default)
			)
			(layer "B.Fab")
		)
		(fp_line
			(start 0.12065 0.2794)
			(end 0.12065 0.3048)
			(stroke
				(width 0.1)
				(type default)
			)
			(layer "B.Fab")
		)
		(fp_line
			(start -0.12065 -0.2794)
			(end -0.12065 -0.3048)
			(stroke
				(width 0.1)
				(type default)
			)
			(layer "B.Fab")
		)
		(fp_line
			(start 0.12065 -0.2794)
			(end -0.12065 -0.2794)
			(stroke
				(width 0.1)
				(type default)
			)
			(layer "B.Fab")
		)
		(fp_line
			(start -0.67945 -0.3048)
			(end -0.67945 0.3048)
			(stroke
				(width 0.1)
				(type default)
			)
			(layer "B.Fab")
		)
		(fp_line
			(start -0.12065 -0.3048)
			(end -0.67945 -0.3048)
			(stroke
				(width 0.1)
				(type default)
			)
			(layer "B.Fab")
		)
		(fp_line
			(start 0.12065 -0.305054)
			(end 0.12065 -0.2794)
			(stroke
				(width 0.1)
				(type default)
			)
			(layer "B.Fab")
		)
		(fp_line
			(start 0.67945 -0.305054)
			(end 0.12065 -0.305054)
			(stroke
				(width 0.1)
				(type default)
			)
			(layer "B.Fab")
		)
		(pad "1" smd circle
			(at 0.40005 0 90)
			(size 0 0)
			(layers "B.Cu" "B.Mask" "B.Paste")
			(net "PVCCFA_EHV_FIVRA_CPU0_VOS1")
		)
		(pad "2" smd circle
			(at -0.40005 0 90)
			(size 0 0)
			(layers "B.Cu" "B.Mask" "B.Paste")
			(net "PVCCFA_EHV_FIVRA_CPU0")
		)
	)
)
